FILE_TYPE = CONNECTIVITY;
{Allegro Design Entry HDL 17.2-2016 S066 (3851973) 4/6/2020}
"PAGE_NUMBER" = 3;
0"NC";
1"XP3R3V\g";
2"SG\g";
3"XP3R3V\g";
4"XP3R3V_PCIE\g";
5"SG\g";
6"SG\g";
7"PCIE_PERST_N";
8"CPU_RX_PCIE_MGT1_TXN";
9"C_CPU_RX_PCIE_MGT3_TXN";
10"CPU_RX_PCIE_MGT2_TXN";
11"FPGA_TCK";
12"FPGA_TDI";
13"PCIE_CONN_SMDAT";
14"UN$3$CONN64PGF$I61$PRSNT21";
15"C_PCIEREFCLKP";
16"C_CPU_RX_PCIE_MGT0_TXP";
17"C_CPU_RX_PCIE_MGT1_TXP";
18"PCIE_CONN_TDI";
19"PCIE_CONN_TDO";
20"FPGA_TMS";
21"CARD_PRESENT";
22"C_CPU_RX_PCIE_MGT2_TXP";
23"C_CPU_RX_PCIE_MGT2_TXN";
24"CPU_RX_PCIE_MGT0_TXP";
25"CPU_RX_PCIE_MGT0_TXN";
26"PCIE_REFCLKP";
27"PCIE_REFCLKN";
28"C_CPU_RX_PCIE_MGT1_TXN";
29"C_CPU_RX_PCIE_MGT0_TXN";
30"FPGA_OUT_I2C_BUFFER_EN";
31"UN$3$G2201019801$I100$EN";
32"UN$3$CONN64PGF$I61$PRSNT22";
33"CPU_TX_PCIE_MGT_0_RXP";
34"CPU_TX_PCIE_MGT_1_RXN";
35"CPU_TX_PCIE_MGT_2_RXP";
36"CPU_TX_PCIE_MGT_3_RXN";
37"CPU_TX_PCIE_MGT_3_RXP";
38"C_PCIEREFCLKN";
39"CPU_RX_PCIE_MGT1_TXP";
40"CPU_RX_PCIE_MGT3_TXP";
41"PCIE_CONN_TCK";
42"FPGA_TDO";
43"PCIE_SMCLK";
44"CPU_TX_PCIE_MGT_1_RXP";
45"CPU_TX_PCIE_MGT_2_RXN";
46"C_CPU_RX_PCIE_MGT3_TXP";
47"CPU_RX_PCIE_MGT2_TXP";
48"PCIE_CONN_PERST_N";
49"PCIE_CONN_TMS";
50"PCIE_CONN_SMDAT";
51"PCIE_CONN_SMCLK";
52"CPU_TX_PCIE_MGT_0_RXN";
53"UN$3$RESISTOR$I151$2";
54"CPU_RX_PCIE_MGT3_TXN";
55"CARD_PRESENT";
56"FPGA_PROGRAM_N";
57"BF_PCIE_PERST_N";
58"CARD_PRESENT";
59"PCIE_CONN_SMCLK";
60"SG\g";
61"XP3R3V_FPGA\g";
62"SG\g";
63"SG\g";
64"XP3R3V_PCIE\g";
65"XP3R3V_AUX_PCIE\g";
66"XP3R3V_FPGA\g";
67"XP3R3V_FPGA\g";
68"SG\g";
69"XP3R3V_AUX_PCIE\g";
70"XP12R0V_PCIE\g";
71"SG\g";
72"XP3R3V_PCIE\g";
73"XP3R3V_FPGA\g";
74"PCIE_SMDAT";
75"PCIE_PERST_N";
76"FPGA_IN_RST_DLY_N";
77"SG\g";
%"GND_SG"
"1","(-750,5250)","0","cls","I1";
;
HDL_POWER"SG"
CDS_LMAN_SYM_OUTLINE"0,0,100,-50"
CDS_LIB"cls"
BODY_TYPE"PLUMBING";
"SGND"60;
%"G220_10198_01"
"1","(-6700,2400)","0","stdlogic","I100";
;
$LOCATION"U2"
CDS_LOCATION"U2"
$SEC"1"
CDS_SEC"1"
NO_ASSY"TRUE"
CLS_PN"G223-10197-01"
PART_NUMBER"PCA9510AD,118"
CDS_LMAN_SYM_OUTLINE"0,0,700,-700"
CDS_LIB"stdlogic";
"VCC"
$PN"8"73;
"SDAOUT"
$PN"7"74;
"SDAIN"
$PN"6"50;
"READY"
$PN"5"0;
"GND"
$PN"4"6;
"SCLIN"
$PN"3"51;
"SCLOUT"
$PN"2"43;
"EN"
$PN"1"31;
%"RESISTOR"
"2","(-7350,2600)","0","passive","I103";
;
$LOCATION"R25"
CDS_LOCATION"R25"
$SEC"1"
CDS_SEC"1"
PACKAGE"0402"
VALUE"4.7KOHM"
NO_ASSY"TRUE"
TOLERANCE"1%"
CLS_PN"G155-14701-01"
CDS_LMAN_SYM_OUTLINE"-50,50,50,-100"
CDS_LIB"passive";
"1"
$PN"1"73;
"2"
$PN"2"31;
%"VCC"
"1","(-750,6250)","0","cls","I111";
;
HDL_POWER"XP3R3V_FPGA"
VOLTAGE"3.3V"
CDS_LMAN_SYM_OUTLINE"-250,250,250,-250"
CDS_LIB"cls"
BODY_TYPE"PLUMBING";
"$PIN0"61;
%"VCC"
"1","(-7950,3000)","0","cls","I112";
;
HDL_POWER"XP3R3V_FPGA"
VOLTAGE"3.3V"
BODY_TYPE"PLUMBING"
CDS_LMAN_SYM_OUTLINE"-250,250,250,-250"
CDS_LIB"cls";
"$PIN0"73;
%"RESISTOR"
"1","(-7900,2100)","0","passive","I114";
;
$LOCATION"R354"
CDS_LOCATION"R354"
$SEC"1"
CDS_SEC"1"
VALUE"33OHM"
PACKAGE"0402"
NO_ASSY"TRUE"
TOLERANCE"1%"
CLS_PN"G155-133R0-01"
CDS_LIB"passive"
CDS_LMAN_SYM_OUTLINE"-50,50,100,-50"
SIGNAL_MODEL"DEFAULT_RESISTOR_33OHM_2_1";
"1"
$PN"1"30;
"2"
$PN"2"31;
%"CAPACITOR"
"1","(-4000,6450)","0","passive","I115";
;
LOCATION"C25"
$SEC"1"
CDS_SEC"1"
VALUE"0.1UF"
PACKAGE"0402"
TOLERANCE"10%"
SIGNAL_MODEL"DEFAULT_CAPACITOR_100000pF_1_2"
CLS_PN"G105-0B104-CK"
CDS_LMAN_SYM_OUTLINE"0,50,50,-50"
CDS_LIB"passive";
"2"
$PN"2"25;
"1"
$PN"1"29;
%"CAPACITOR"
"1","(-4000,6050)","0","passive","I116";
;
LOCATION"C26"
$SEC"1"
CDS_SEC"1"
PACKAGE"0402"
VALUE"0.1UF"
TOLERANCE"10%"
SIGNAL_MODEL"DEFAULT_CAPACITOR_100000pF_1_2"
CLS_PN"G105-0B104-CK"
CDS_LMAN_SYM_OUTLINE"0,50,50,-50"
CDS_LIB"passive";
"2"
$PN"2"39;
"1"
$PN"1"17;
%"CAPACITOR"
"1","(-4000,5950)","0","passive","I117";
;
LOCATION"C27"
$SEC"1"
CDS_SEC"1"
VALUE"0.1UF"
PACKAGE"0402"
TOLERANCE"10%"
SIGNAL_MODEL"DEFAULT_CAPACITOR_100000pF_1_2"
CLS_PN"G105-0B104-CK"
CDS_LMAN_SYM_OUTLINE"0,50,50,-50"
CDS_LIB"passive";
"2"
$PN"2"8;
"1"
$PN"1"28;
%"CAPACITOR"
"1","(-4000,5650)","0","passive","I118";
;
LOCATION"C28"
$SEC"1"
CDS_SEC"1"
VALUE"0.1UF"
PACKAGE"0402"
TOLERANCE"10%"
SIGNAL_MODEL"DEFAULT_CAPACITOR_100000pF_1_2"
CLS_PN"G105-0B104-CK"
CDS_LMAN_SYM_OUTLINE"0,50,50,-50"
CDS_LIB"passive";
"2"
$PN"2"47;
"1"
$PN"1"22;
%"CAPACITOR"
"1","(-4000,5550)","0","passive","I119";
;
LOCATION"C34"
$SEC"1"
CDS_SEC"1"
PACKAGE"0402"
VALUE"0.1UF"
TOLERANCE"10%"
SIGNAL_MODEL"DEFAULT_CAPACITOR_100000pF_1_2"
CLS_PN"G105-0B104-CK"
CDS_LMAN_SYM_OUTLINE"0,50,50,-50"
CDS_LIB"passive";
"2"
$PN"2"10;
"1"
$PN"1"23;
%"CAPACITOR"
"1","(-4000,5250)","0","passive","I120";
;
LOCATION"C35"
$SEC"1"
CDS_SEC"1"
VALUE"0.1UF"
PACKAGE"0402"
TOLERANCE"10%"
SIGNAL_MODEL"DEFAULT_CAPACITOR_100000pF_1_2"
CLS_PN"G105-0B104-CK"
CDS_LMAN_SYM_OUTLINE"0,50,50,-50"
CDS_LIB"passive";
"2"
$PN"2"40;
"1"
$PN"1"46;
%"CAPACITOR"
"1","(-4000,5150)","0","passive","I121";
;
LOCATION"C36"
$SEC"1"
CDS_SEC"1"
PACKAGE"0402"
VALUE"0.1UF"
CDS_LIB"passive"
CDS_LMAN_SYM_OUTLINE"0,50,50,-50"
CLS_PN"G105-0B104-CK"
SIGNAL_MODEL"DEFAULT_CAPACITOR_100000pF_1_2"
TOLERANCE"10%";
"2"
$PN"2"54;
"1"
$PN"1"9;
%"RESISTOR"
"1","(900,7150)","0","passive","I122";
;
$LOCATION"R356"
CDS_LOCATION"R356"
$SEC"1"
CDS_SEC"1"
VALUE"0OHM"
PACKAGE"0402"
CDS_LMAN_SYM_OUTLINE"-50,50,100,-50"
CDS_LIB"passive"
CLS_PN"G155-100R0-J0"
TOLERANCE"-";
"1"
$PN"1"57;
"2"
$PN"2"56;
%"CAPACITOR"
"2","(-5900,3900)","2","passive","I124";
;
$LOCATION"C289"
CDS_LOCATION"C289"
$SEC"1"
CDS_SEC"1"
VALUE"10UF"
PACKAGE"0402"
VOLTAGE"6.3V"
TOLERANCE"20%"
CLS_PN"G105-0C106-BM"
CDS_LMAN_SYM_OUTLINE"-50,0,50,-50"
CDS_LIB"passive";
"2"
$PN"2"62;
"1"
$PN"1"64;
%"GND_SG"
"1","(-5850,3500)","2","cls","I125";
;
HDL_POWER"SG"
CDS_LMAN_SYM_OUTLINE"0,0,100,-50"
CDS_LIB"cls"
BODY_TYPE"PLUMBING";
"SGND"62;
%"CAPACITOR"
"2","(-5500,3900)","2","passive","I126";
;
$LOCATION"C290"
CDS_LOCATION"C290"
$SEC"1"
CDS_SEC"1"
VOLTAGE"25V"
PACKAGE"0402"
VALUE"0.1UF"
TOLERANCE"10%"
CLS_PN"G105-0B104-EK"
CDS_LIB"passive"
CDS_LMAN_SYM_OUTLINE"-50,0,50,-50";
"2"
$PN"2"62;
"1"
$PN"1"64;
%"CAPACITOR"
"2","(-6650,3900)","2","passive","I127";
;
$LOCATION"C288"
CDS_LOCATION"C288"
$SEC"1"
CDS_SEC"1"
PACKAGE"0402"
VALUE"0.1UF"
VOLTAGE"25V"
CDS_LIB"passive"
CDS_LMAN_SYM_OUTLINE"-50,0,50,-50"
TOLERANCE"10%"
CLS_PN"G105-0B104-EK";
"2"
$PN"2"63;
"1"
$PN"1"65;
%"GND_SG"
"1","(-7000,3500)","2","cls","I128";
;
HDL_POWER"SG"
CDS_LIB"cls"
CDS_LMAN_SYM_OUTLINE"0,0,100,-50"
BODY_TYPE"PLUMBING";
"SGND"63;
%"CAPACITOR"
"2","(-7050,3900)","2","passive","I129";
;
$LOCATION"C287"
CDS_LOCATION"C287"
$SEC"1"
CDS_SEC"1"
VALUE"10UF"
PACKAGE"0402"
VOLTAGE"6.3V"
CDS_LIB"passive"
CDS_LMAN_SYM_OUTLINE"-50,0,50,-50"
CLS_PN"G105-0C106-BM"
TOLERANCE"20%";
"2"
$PN"2"63;
"1"
$PN"1"65;
%"VCC"
"1","(-5950,4250)","0","cls","I130";
;
HDL_POWER"XP3R3V_PCIE"
VOLTAGE"3.3"
CDS_LIB"cls"
CDS_LMAN_SYM_OUTLINE"-250,250,250,-250"
BODY_TYPE"PLUMBING";
"$PIN0"64;
%"VCC"
"1","(-7100,4200)","0","cls","I131";
;
HDL_POWER"XP3R3V_AUX_PCIE"
VOLTAGE"3.3"
CDS_LMAN_SYM_OUTLINE"-250,250,250,-250"
CDS_LIB"cls"
BODY_TYPE"PLUMBING";
"$PIN0"65;
%"FERRITEBEAD"
"1","(-5150,4150)","0","passive","I132";
;
$LOCATION"L21"
CDS_LOCATION"L21"
$SEC"1"
CDS_SEC"1"
NO_ASSY"TRUE"
PACKAGE"0603"
VALUE"26OHM"
CLS_PN"G191-10101-01"
TOLERANCE"25%"
CDS_LMAN_SYM_OUTLINE"0,0,200,-100"
CDS_LIB"passive";
"2"
$PN"2"1;
"1"
$PN"1"64;
%"VCC"
"1","(-4500,4300)","0","cls","I133";
;
VOLTAGE"3.3"
HDL_POWER"XP3R3V"
CDS_LIB"cls"
CDS_LMAN_SYM_OUTLINE"-250,250,250,-250"
BODY_TYPE"PLUMBING";
"$PIN0"1;
%"74LVC1G07_SC70_5"
"1","(-900,7300)","0","stdlogic","I134";
;
LOCATION"U3"
$SEC"1"
CDS_SEC"1"
CLS_PN"G220-10017-01"
PART_NUMBER"SN74LVC1G07DCKRG4"
CDS_LIB"stdlogic"
CDS_LMAN_SYM_OUTLINE"0,0,350,-450";
"Y"
$PN"4"57;
"A"
$PN"2"48;
"NC"
$PN"1"0;
%"74LVC1G07_SC70_5"
"2","(-900,6000)","0","stdlogic","I135";
;
LOCATION"U3"
$SEC"2"
CDS_SEC"2"
CLS_PN"G220-10017-01"
PART_NUMBER"SN74LVC1G07DCKRG4"
CDS_LIB"stdlogic"
CDS_LMAN_SYM_OUTLINE"0,0,400,-500";
"VCC"
$PN"5"61;
"GND"
$PN"3"60;
%"TPS3808G18DBVR_SOT23_6"
"1","(-450,3750)","0","analog","I139";
;
$LOCATION"U34"
CDS_LOCATION"U34"
$SEC"1"
CDS_SEC"1"
CLS_PN"G222-00082-01"
PART_NUMBER"TPS3808G33DBVRG4"
CDS_LMAN_SYM_OUTLINE"0,0,700,-600"
CDS_LIB"analog";
"VDD"
$PN"6"66;
"SENSE"
$PN"5"66;
"CT"
$PN"4"53;
"MR* \B"
$PN"3"75;
"RESET* \B"
$PN"1"76;
"GND"
$PN"2"77;
%"VCC"
"1","(-750,4100)","0","cls","I140";
;
VOLTAGE"3.3V"
HDL_POWER"XP3R3V_FPGA"
CDS_LMAN_SYM_OUTLINE"-250,250,250,-250"
CDS_LIB"cls"
BODY_TYPE"PLUMBING";
"$PIN0"66;
%"RESISTOR"
"2","(-1350,3650)","0","passive","I144";
;
$LOCATION"R63"
CDS_LOCATION"R63"
$SEC"1"
CDS_SEC"1"
PACKAGE"0402"
VALUE"4.7KOHM"
TOLERANCE"1%"
CLS_PN"G155-14701-01"
CDS_LMAN_SYM_OUTLINE"-50,50,50,-100"
CDS_LIB"passive";
"1"
$PN"1"66;
"2"
$PN"2"75;
%"RESISTOR"
"2","(850,4000)","0","passive","I148";
;
$LOCATION"R167"
CDS_LOCATION"R167"
$SEC"1"
CDS_SEC"1"
VALUE"10KOHM"
PACKAGE"0402"
CLS_PN"G155-11002-01"
TOLERANCE"1%"
CDS_LMAN_SYM_OUTLINE"-50,50,50,-100"
CDS_LIB"passive";
"1"
$PN"1"67;
"2"
$PN"2"76;
%"VCC"
"1","(800,4350)","0","cls","I149";
;
VOLTAGE"3.3V"
HDL_POWER"XP3R3V_FPGA"
BODY_TYPE"PLUMBING"
CDS_LMAN_SYM_OUTLINE"-250,250,250,-250"
CDS_LIB"cls";
"$PIN0"67;
%"RESISTOR"
"1","(-8250,5050)","0","passive","I15";
;
$LOCATION"R23"
CDS_LOCATION"R23"
$SEC"1"
CDS_SEC"1"
PACKAGE"0402"
VALUE"0OHM"
CDS_LIB"passive"
CDS_LMAN_SYM_OUTLINE"-50,50,100,-50"
CLS_PN"G155-100R0-J0"
TOLERANCE"-";
"1"
$PN"1"58;
"2"
$PN"2"32;
%"GND_SG"
"1","(400,3050)","0","cls","I150";
;
HDL_POWER"SG"
CDS_LIB"cls"
CDS_LMAN_SYM_OUTLINE"0,0,100,-50"
BODY_TYPE"PLUMBING";
"SGND"77;
%"RESISTOR"
"2","(450,4000)","0","passive","I151";
;
$LOCATION"R164"
CDS_LOCATION"R164"
$SEC"1"
CDS_SEC"1"
VALUE"100KOHM"
NO_ASSY"TRUE"
PACKAGE"0402"
CDS_LIB"passive"
CDS_LMAN_SYM_OUTLINE"-50,50,50,-100"
TOLERANCE"1%"
CLS_PN"G155-11003-01";
"1"
$PN"1"67;
"2"
$PN"2"53;
%"CAPACITOR"
"2","(650,3350)","2","passive","I152";
;
$LOCATION"C250"
CDS_LOCATION"C250"
$SEC"1"
CDS_SEC"1"
PACKAGE"0402"
VOLTAGE"25V"
VALUE"0.1UF"
CDS_LIB"passive"
CDS_LMAN_SYM_OUTLINE"-50,0,50,-50"
TOLERANCE"10%"
CLS_PN"G105-0B104-EK";
"2"
$PN"2"77;
"1"
$PN"1"53;
%"RESISTOR"
"1","(900,7000)","0","passive","I153";
;
$LOCATION"R57"
CDS_LOCATION"R57"
$SEC"1"
CDS_SEC"1"
VALUE"33OHM"
PACKAGE"0402"
CDS_LIB"passive"
CDS_LMAN_SYM_OUTLINE"-50,50,100,-50"
CLS_PN"G155-133R0-01"
TOLERANCE"1%";
"1"
$PN"1"57;
"2"
$PN"2"7;
%"RESISTOR"
"1","(-8400,6450)","0","passive","I16";
;
$LOCATION"R22"
CDS_LOCATION"R22"
$SEC"1"
CDS_SEC"1"
VALUE"0OHM"
PACKAGE"0402"
NO_ASSY"TRUE"
CDS_LIB"passive"
CDS_LMAN_SYM_OUTLINE"-50,50,100,-50"
CLS_PN"G155-100R0-J0"
TOLERANCE"-";
"1"
$PN"1"55;
"2"
$PN"2"14;
%"GND_SG"
"1","(-1300,6350)","0","cls","I18";
;
HDL_POWER"SG"
CDS_LMAN_SYM_OUTLINE"0,0,100,-50"
CDS_LIB"cls"
BODY_TYPE"PLUMBING";
"SGND"2;
%"VCC"
"1","(-1350,7900)","0","cls","I19";
;
VOLTAGE"3.3"
HDL_POWER"XP3R3V"
CDS_LIB"cls"
CDS_LMAN_SYM_OUTLINE"-250,250,250,-250"
BODY_TYPE"PLUMBING";
"$PIN0"3;
%"GND_SG"
"1","(-7350,4750)","0","cls","I20";
;
HDL_POWER"SG"
BODY_TYPE"PLUMBING"
CDS_LIB"cls"
CDS_LMAN_SYM_OUTLINE"0,0,100,-50";
"SGND"68;
%"VCC"
"1","(-8700,8850)","0","cls","I23";
;
VOLTAGE"3.3"
HDL_POWER"XP3R3V_AUX_PCIE"
CDS_LIB"cls"
CDS_LMAN_SYM_OUTLINE"-250,250,250,-250"
BODY_TYPE"PLUMBING";
"$PIN0"69;
%"VCC"
"1","(-8000,8850)","0","cls","I24";
;
VOLTAGE"3.3"
HDL_POWER"XP3R3V_PCIE"
CDS_LIB"cls"
CDS_LMAN_SYM_OUTLINE"-250,250,250,-250"
BODY_TYPE"PLUMBING";
"$PIN0"4;
%"VCC"
"1","(-7400,8850)","0","cls","I25";
;
HDL_POWER"XP12R0V_PCIE"
VOLTAGE"12"
CDS_LMAN_SYM_OUTLINE"-250,250,250,-250"
CDS_LIB"cls"
BODY_TYPE"PLUMBING";
"$PIN0"70;
%"GND_SG"
"1","(-5750,4750)","0","cls","I26";
;
HDL_POWER"SG"
BODY_TYPE"PLUMBING"
CDS_LIB"cls"
CDS_LMAN_SYM_OUTLINE"0,0,100,-50";
"SGND"71;
%"CAPACITOR"
"1","(-4000,6550)","0","passive","I35";
;
$LOCATION"C24"
CDS_LOCATION"C24"
$SEC"1"
CDS_SEC"1"
PACKAGE"0402"
VALUE"0.1UF"
TOLERANCE"10%"
SIGNAL_MODEL"DEFAULT_CAPACITOR_100000pF_1_2"
CLS_PN"G105-0B104-CK"
CDS_LMAN_SYM_OUTLINE"0,50,50,-50"
CDS_LIB"passive";
"2"
$PN"2"24;
"1"
$PN"1"16;
%"CAPACITOR"
"1","(-4000,6850)","0","passive","I36";
;
$LOCATION"C19"
CDS_LOCATION"C19"
$SEC"1"
CDS_SEC"1"
VALUE"0.1UF"
PACKAGE"0402"
TOLERANCE"10%"
SIGNAL_MODEL"DEFAULT_CAPACITOR_100000pF_1_2"
CLS_PN"G105-0B104-CK"
CDS_LMAN_SYM_OUTLINE"0,50,50,-50"
CDS_LIB"passive";
"2"
$PN"2"26;
"1"
$PN"1"15;
%"CAPACITOR"
"1","(-4000,6750)","0","passive","I37";
;
$LOCATION"C23"
CDS_LOCATION"C23"
$SEC"1"
CDS_SEC"1"
PACKAGE"0402"
VALUE"0.1UF"
CDS_LIB"passive"
CDS_LMAN_SYM_OUTLINE"0,50,50,-50"
CLS_PN"G105-0B104-CK"
SIGNAL_MODEL"DEFAULT_CAPACITOR_100000pF_1_2"
TOLERANCE"10%";
"2"
$PN"2"27;
"1"
$PN"1"38;
%"CAPACITOR"
"2","(-250,5800)","0","passive","I4";
;
$LOCATION"C37"
CDS_LOCATION"C37"
$SEC"1"
CDS_SEC"1"
VALUE"0.1UF"
VOLTAGE"10V"
PACKAGE"0402"
TOLERANCE"10%"
CLS_PN"G105-0B104-CK"
CDS_LMAN_SYM_OUTLINE"-50,0,50,-50"
CDS_LIB"passive";
"2"
$PN"2"60;
"1"
$PN"1"61;
%"VCC"
"1","(-5550,8850)","0","cls","I49";
;
VOLTAGE"3.3"
HDL_POWER"XP3R3V_PCIE"
BODY_TYPE"PLUMBING"
CDS_LIB"cls"
CDS_LMAN_SYM_OUTLINE"-250,250,250,-250";
"$PIN0"72;
%"RESISTOR"
"1","(-3950,7450)","0","passive","I51";
;
$LOCATION"R43"
CDS_LOCATION"R43"
$SEC"1"
CDS_SEC"1"
PACKAGE"0402"
NO_ASSY"TRUE"
VALUE"0OHM"
CDS_LMAN_SYM_OUTLINE"-50,50,100,-50"
CDS_LIB"passive"
CLS_PN"G155-100R0-J0"
TOLERANCE"-";
"1"
$PN"1"49;
"2"
$PN"2"20;
%"RESISTOR"
"1","(-3950,7550)","0","passive","I52";
;
$LOCATION"R42"
CDS_LOCATION"R42"
$SEC"1"
CDS_SEC"1"
NO_ASSY"TRUE"
PACKAGE"0402"
VALUE"0OHM"
CDS_LIB"passive"
CDS_LMAN_SYM_OUTLINE"-50,50,100,-50"
CLS_PN"G155-100R0-J0"
TOLERANCE"-";
"1"
$PN"1"19;
"2"
$PN"2"42;
%"RESISTOR"
"1","(-3950,7650)","0","passive","I53";
;
$LOCATION"R41"
CDS_LOCATION"R41"
$SEC"1"
CDS_SEC"1"
PACKAGE"0402"
NO_ASSY"TRUE"
VALUE"0OHM"
CLS_PN"G155-100R0-J0"
CDS_LMAN_SYM_OUTLINE"-50,50,100,-50"
CDS_LIB"passive"
TOLERANCE"-";
"1"
$PN"1"18;
"2"
$PN"2"12;
%"RESISTOR"
"1","(-3950,7750)","0","passive","I54";
;
$LOCATION"R28"
CDS_LOCATION"R28"
$SEC"1"
CDS_SEC"1"
PACKAGE"0402"
NO_ASSY"TRUE"
VALUE"0OHM"
CLS_PN"G155-100R0-J0"
CDS_LMAN_SYM_OUTLINE"-50,50,100,-50"
CDS_LIB"passive"
TOLERANCE"-";
"1"
$PN"1"41;
"2"
$PN"2"11;
%"CONN_64P_GF"
"1","(-7050,8350)","0","connector","I61";
;
$LOCATION"GF1"
CDS_LOCATION"GF1"
$SEC"1"
CDS_SEC"1"
CLS_PN"S_M_EF64_PCIE_P0394_V1"
NO_ASSY"TRUE"
CDS_LMAN_SYM_OUTLINE"0,0,1100,-3500"
CDS_LIB"connector";
"RSVD4"
$PN"A32"0;
"GND21"
$PN"A31"71;
"PERN3"
$PN"A30"9;
"PERP3"
$PN"A29"46;
"GND19"
$PN"A28"71;
"GND18"
$PN"A27"71;
"PERN2"
$PN"A26"23;
"PERP2"
$PN"A25"22;
"GND14"
$PN"A24"71;
"GND13"
$PN"A23"71;
"PERN1"
$PN"A22"28;
"PERP1"
$PN"A21"17;
"GND10"
$PN"A20"71;
"RSVD2"
$PN"A19"0;
"GND8"
$PN"A18"71;
"PERN0"
$PN"A17"29;
"PERP0"
$PN"A16"16;
"GND6"
$PN"A15"71;
"REFCLK_N"
$PN"A14"38;
"REFCLK_P"
$PN"A13"15;
"GND4"
$PN"A12"71;
"PERST* \B"
$PN"A11"48;
"P_3V3_3"
$PN"A10"72;
"P_3V3_2"
$PN"A9"72;
"JTAG5"
$PN"A8"49;
"JTAG4"
$PN"A7"19;
"JTAG3"
$PN"A6"18;
"JTAG2"
$PN"A5"41;
"GND2"
$PN"A4"71;
"P_12V5"
$PN"A3"70;
"P_12V3"
$PN"A2"70;
"PRSNT1* \B"
$PN"A1"21;
"GND22"
$PN"B32"68;
"PRSNT2_2* \B"
$PN"B31"32;
"RSVD3"
$PN"B30"0;
"GND20"
$PN"B29"68;
"PETN3"
$PN"B28"36;
"PETP3"
$PN"B27"37;
"GND17"
$PN"B26"68;
"GND15"
$PN"B25"68;
"PETN2"
$PN"B24"45;
"PETP2"
$PN"B23"35;
"GND12"
$PN"B22"68;
"GND11"
$PN"B21"68;
"PETN1"
$PN"B20"34;
"PETP1"
$PN"B19"44;
"GND9"
$PN"B18"68;
"PRSNT2_1* \B"
$PN"B17"14;
"GND7"
$PN"B16"68;
"PETN0"
$PN"B15"52;
"PETP0"
$PN"B14"33;
"GND5"
$PN"B13"68;
"RSVD1"
$PN"B12"0;
"WAKE* \B"
$PN"B11"0;
"P_3V3AUX"
$PN"B10"69;
"JTAG1"
$PN"B9"0;
"P_3V3_1"
$PN"B8"4;
"GND3"
$PN"B7"68;
"SMDAT"
$PN"B6"13;
"SMCLK"
$PN"B5"59;
"GND1"
$PN"B4"68;
"P_12V4"
$PN"B3"70;
"P_12V2"
$PN"B2"70;
"P_12V1"
$PN"B1"70;
%"RESISTOR"
"2","(-1250,6700)","0","passive","I62";
;
$LOCATION"R55"
CDS_LOCATION"R55"
$SEC"1"
CDS_SEC"1"
VALUE"4.7KOHM"
PACKAGE"0402"
NO_ASSY"TRUE"
CDS_LIB"passive"
CDS_LMAN_SYM_OUTLINE"-50,50,50,-100"
CLS_PN"G155-14701-01"
TOLERANCE"1%";
"1"
$PN"1"48;
"2"
$PN"2"2;
%"RESISTOR"
"2","(-1300,7600)","0","passive","I63";
;
$LOCATION"R56"
CDS_LOCATION"R56"
$SEC"1"
CDS_SEC"1"
VALUE"4.7KOHM"
PACKAGE"0402"
CLS_PN"G155-14701-01"
CDS_LMAN_SYM_OUTLINE"-50,50,50,-100"
CDS_LIB"passive"
TOLERANCE"1%";
"1"
$PN"1"3;
"2"
$PN"2"48;
%"GND_SG"
"1","(-7950,2400)","0","cls","I91";
;
HDL_POWER"SG"
BODY_TYPE"PLUMBING"
CDS_LIB"cls"
CDS_LMAN_SYM_OUTLINE"0,0,100,-50"
VOLTAGE"0";
"SGND"5;
%"CAPACITOR"
"2","(-7900,2700)","0","passive","I92";
;
$LOCATION"C17"
CDS_LOCATION"C17"
$SEC"1"
CDS_SEC"1"
PACKAGE"0402"
NO_ASSY"TRUE"
VALUE"0.1UF"
TOLERANCE"10%"
CLS_PN"G105-0B104-CK"
CDS_LMAN_SYM_OUTLINE"-50,0,50,-50"
CDS_LIB"passive";
"2"
$PN"2"5;
"1"
$PN"1"73;
%"GND_SG"
"1","(-5750,1600)","0","cls","I94";
;
HDL_POWER"SG"
BODY_TYPE"PLUMBING"
CDS_LMAN_SYM_OUTLINE"0,0,100,-50"
CDS_LIB"cls";
"SGND"6;
END.
